(kicad_pcb
	(version 20260206)
	(generator "pcbnew")
	(generator_version "10.0")
	(general
		(thickness 1.6)
		(legacy_teardrops no)
	)
	(paper "A4")
	(title_block
		(title "01162023_DA0F0TEBIF0_F0T_Expander_BD_F_brd_V02_OCP.brd")
		(comment 1 "Grand Teton / footprint 5622 of 9728 (PEX2), pads 2000-2119 of 2397")
	)
	(layers
		(0 "F.Cu" signal "TOP")
		(4 "In1.Cu" signal "GND")
		(6 "In2.Cu" signal "VCC")
		(8 "In3.Cu" signal "VCC1")
		(10 "In4.Cu" signal "GND1")
		(12 "In5.Cu" signal "IN1")
		(14 "In6.Cu" signal "GND2")
		(16 "In7.Cu" signal "IN2")
		(18 "In8.Cu" signal "GND3")
		(20 "In9.Cu" signal "IN3")
		(22 "In10.Cu" signal "GND4")
		(24 "In11.Cu" signal "IN4")
		(26 "In12.Cu" signal "GND5")
		(28 "In13.Cu" signal "IN5")
		(30 "In14.Cu" signal "GND6")
		(32 "In15.Cu" signal "IN6")
		(34 "In16.Cu" signal "GND7")
		(2 "B.Cu" signal "BOTTOM")
		(9 "F.Adhes" user "F.Adhesive")
		(11 "B.Adhes" user "B.Adhesive")
		(13 "F.Paste" user "Package Geometry/Pastemask Top")
		(15 "B.Paste" user "Package Geometry/Pastemask Bottom")
		(5 "F.SilkS" user "Ref Des/Silkscreen Top")
		(7 "B.SilkS" user "Ref Des/Silkscreen Bottom")
		(1 "F.Mask" user "Board Geometry/Soldermask Top")
		(3 "B.Mask" user "Board Geometry/Soldermask Bottom")
		(17 "Dwgs.User" user "User.Drawings")
		(19 "Cmts.User" user "User.Comments")
		(21 "Eco1.User" user "User.Eco1")
		(23 "Eco2.User" user "User.Eco2")
		(25 "Edge.Cuts" user "Board Geometry/Outline")
		(27 "Margin" user)
		(31 "F.CrtYd" user "Package Geometry/Place Bound Top")
		(29 "B.CrtYd" user "Package Geometry/Place Bound Bottom")
		(35 "F.Fab" user "Ref Des/Assembly Top")
		(33 "B.Fab" user "Ref Des/Assembly Bottom")
	)
	(footprint ""
		(layer "F.Cu")
		(at 291.84981 -295.89984)
		(property "Reference" "PEX2"
			(at -3.35153 35.56762 0)
			(unlocked yes)
			(layer "F.SilkS")
			(effects
				(font
					(size 2.032 1.524)
					(thickness 0.1524)
				)
				(justify left)
			)
		)
		(property "Value" ""
			(at 0 0 0)
			(layer "F.Fab")
			(effects
				(font
					(size 1.27 1.27)
				)
			)
		)
		(duplicate_pad_numbers_are_jumpers no)
		(pad "M44" smd circle
			(at 18.050002 -12.349988)
			(size 0.4572 0.4572)
			(layers "F.Cu" "F.Mask" "F.Paste")
			(net "GND")
		)
		(pad "M45" smd circle
			(at 18.999962 -12.349988)
			(size 0.4572 0.4572)
			(layers "F.Cu" "F.Mask" "F.Paste")
			(net "GND")
		)
		(pad "M46" smd circle
			(at 19.949922 -12.349988)
			(size 0.4572 0.4572)
			(layers "F.Cu" "F.Mask" "F.Paste")
			(net "GND")
		)
		(pad "M47" smd circle
			(at 20.899882 -12.349988)
			(size 0.4572 0.4572)
			(layers "F.Cu" "F.Mask" "F.Paste")
			(net "GND")
		)
		(pad "M48" smd circle
			(at 21.850096 -12.349988)
			(size 0.4572 0.4572)
			(layers "F.Cu" "F.Mask" "F.Paste")
			(net "P5E_PEX2_STN4_RX_DP<68>")
		)
		(pad "M49" smd circle
			(at 22.800056 -12.349988)
			(size 0.4572 0.4572)
			(layers "F.Cu" "F.Mask" "F.Paste")
			(net "P5E_PEX2_STN4_RX_DN<68>")
		)
		(pad "N1" smd circle
			(at -22.800056 -11.400028)
			(size 0.4572 0.4572)
			(layers "F.Cu" "F.Mask" "F.Paste")
			(net "GND")
		)
		(pad "N2" smd circle
			(at -21.850096 -11.400028)
			(size 0.4572 0.4572)
			(layers "F.Cu" "F.Mask" "F.Paste")
			(net "GND")
		)
		(pad "N3" smd circle
			(at -20.899882 -11.400028)
			(size 0.4572 0.4572)
			(layers "F.Cu" "F.Mask" "F.Paste")
			(net "P5E_PEX2_STN7_RX_DN<118>")
		)
		(pad "N4" smd circle
			(at -19.949922 -11.400028)
			(size 0.4572 0.4572)
			(layers "F.Cu" "F.Mask" "F.Paste")
			(net "P5E_PEX2_STN7_RX_DP<118>")
		)
		(pad "N5" smd circle
			(at -18.999962 -11.400028)
			(size 0.4572 0.4572)
			(layers "F.Cu" "F.Mask" "F.Paste")
			(net "GND")
		)
		(pad "N6" smd circle
			(at -18.050002 -11.400028)
			(size 0.4572 0.4572)
			(layers "F.Cu" "F.Mask" "F.Paste")
			(net "P5E_PEX2_STN7_TX_DN<118>")
		)
		(pad "N7" smd circle
			(at -17.100042 -11.400028)
			(size 0.4572 0.4572)
			(layers "F.Cu" "F.Mask" "F.Paste")
			(net "P5E_PEX2_STN7_TX_DP<118>")
		)
		(pad "N8" smd circle
			(at -16.150082 -11.400028)
			(size 0.4572 0.4572)
			(layers "F.Cu" "F.Mask" "F.Paste")
			(net "GND")
		)
		(pad "N9" smd circle
			(at -15.200122 -11.400028)
			(size 0.4572 0.4572)
			(layers "F.Cu" "F.Mask" "F.Paste")
			(net "GND")
		)
		(pad "N10" smd circle
			(at -14.249908 -11.400028)
			(size 0.4572 0.4572)
			(layers "F.Cu" "F.Mask" "F.Paste")
			(net "GND")
		)
		(pad "N11" smd circle
			(at -13.299948 -11.400028)
			(size 0.4572 0.4572)
			(layers "F.Cu" "F.Mask" "F.Paste")
			(net "GND")
		)
		(pad "N12" smd circle
			(at -12.349988 -11.400028)
			(size 0.4572 0.4572)
			(layers "F.Cu" "F.Mask" "F.Paste")
			(net "GND")
		)
		(pad "N13" smd circle
			(at -11.400028 -11.400028)
			(size 0.4572 0.4572)
			(layers "F.Cu" "F.Mask" "F.Paste")
			(net "GND")
		)
		(pad "N14" smd circle
			(at -10.450068 -11.400028)
			(size 0.4572 0.4572)
			(layers "F.Cu" "F.Mask" "F.Paste")
			(net "GND")
		)
		(pad "N15" smd circle
			(at -9.500108 -11.400028)
			(size 0.4572 0.4572)
			(layers "F.Cu" "F.Mask" "F.Paste")
			(net "GND")
		)
		(pad "N16" smd circle
			(at -8.549894 -11.400028)
			(size 0.4572 0.4572)
			(layers "F.Cu" "F.Mask" "F.Paste")
			(net "GND")
		)
		(pad "N17" smd circle
			(at -7.599934 -11.400028)
			(size 0.4572 0.4572)
			(layers "F.Cu" "F.Mask" "F.Paste")
			(net "GND")
		)
		(pad "N18" smd circle
			(at -6.649974 -11.400028)
			(size 0.4572 0.4572)
			(layers "F.Cu" "F.Mask" "F.Paste")
			(net "GND")
		)
		(pad "N19" smd circle
			(at -5.700014 -11.400028)
			(size 0.4572 0.4572)
			(layers "F.Cu" "F.Mask" "F.Paste")
			(net "GND")
		)
		(pad "N20" smd circle
			(at -4.750054 -11.400028)
			(size 0.4572 0.4572)
			(layers "F.Cu" "F.Mask" "F.Paste")
			(net "GND")
		)
		(pad "N21" smd circle
			(at -3.800094 -11.400028)
			(size 0.4572 0.4572)
			(layers "F.Cu" "F.Mask" "F.Paste")
			(net "GND")
		)
		(pad "N22" smd circle
			(at -2.84988 -11.400028)
			(size 0.4572 0.4572)
			(layers "F.Cu" "F.Mask" "F.Paste")
			(net "GND")
		)
		(pad "N23" smd circle
			(at -1.89992 -11.400028)
			(size 0.4572 0.4572)
			(layers "F.Cu" "F.Mask" "F.Paste")
			(net "GND")
		)
		(pad "N24" smd circle
			(at -0.94996 -11.400028)
			(size 0.4572 0.4572)
			(layers "F.Cu" "F.Mask" "F.Paste")
			(net "GND")
		)
		(pad "N25" smd circle
			(at 0 -11.400028)
			(size 0.4572 0.4572)
			(layers "F.Cu" "F.Mask" "F.Paste")
			(net "GND")
		)
		(pad "N26" smd circle
			(at 0.94996 -11.400028)
			(size 0.4572 0.4572)
			(layers "F.Cu" "F.Mask" "F.Paste")
			(net "GND")
		)
		(pad "N27" smd circle
			(at 1.89992 -11.400028)
			(size 0.4572 0.4572)
			(layers "F.Cu" "F.Mask" "F.Paste")
			(net "GND")
		)
		(pad "N28" smd circle
			(at 2.84988 -11.400028)
			(size 0.4572 0.4572)
			(layers "F.Cu" "F.Mask" "F.Paste")
			(net "GND")
		)
		(pad "N29" smd circle
			(at 3.800094 -11.400028)
			(size 0.4572 0.4572)
			(layers "F.Cu" "F.Mask" "F.Paste")
			(net "GND")
		)
		(pad "N30" smd circle
			(at 4.750054 -11.400028)
			(size 0.4572 0.4572)
			(layers "F.Cu" "F.Mask" "F.Paste")
			(net "GND")
		)
		(pad "N31" smd circle
			(at 5.700014 -11.400028)
			(size 0.4572 0.4572)
			(layers "F.Cu" "F.Mask" "F.Paste")
			(net "GND")
		)
		(pad "N32" smd circle
			(at 6.649974 -11.400028)
			(size 0.4572 0.4572)
			(layers "F.Cu" "F.Mask" "F.Paste")
			(net "GND")
		)
		(pad "N33" smd circle
			(at 7.599934 -11.400028)
			(size 0.4572 0.4572)
			(layers "F.Cu" "F.Mask" "F.Paste")
			(net "GND")
		)
		(pad "N34" smd circle
			(at 8.549894 -11.400028)
			(size 0.4572 0.4572)
			(layers "F.Cu" "F.Mask" "F.Paste")
			(net "GND")
		)
		(pad "N35" smd circle
			(at 9.500108 -11.400028)
			(size 0.4572 0.4572)
			(layers "F.Cu" "F.Mask" "F.Paste")
			(net "GND")
		)
		(pad "N36" smd circle
			(at 10.450068 -11.400028)
			(size 0.4572 0.4572)
			(layers "F.Cu" "F.Mask" "F.Paste")
			(net "GND")
		)
		(pad "N37" smd circle
			(at 11.400028 -11.400028)
			(size 0.4572 0.4572)
			(layers "F.Cu" "F.Mask" "F.Paste")
			(net "GND")
		)
		(pad "N38" smd circle
			(at 12.349988 -11.400028)
			(size 0.4572 0.4572)
			(layers "F.Cu" "F.Mask" "F.Paste")
			(net "SMB_PEX2_SLAVE_SCL")
		)
		(pad "N39" smd circle
			(at 13.299948 -11.400028)
			(size 0.4572 0.4572)
			(layers "F.Cu" "F.Mask" "F.Paste")
			(net "Net_5370")
		)
		(pad "N40" smd circle
			(at 14.249908 -11.400028)
			(size 0.4572 0.4572)
			(layers "F.Cu" "F.Mask" "F.Paste")
			(net "GND")
		)
		(pad "N41" smd circle
			(at 15.200122 -11.400028)
			(size 0.4572 0.4572)
			(layers "F.Cu" "F.Mask" "F.Paste")
			(net "GND")
		)
		(pad "N42" smd circle
			(at 16.150082 -11.400028)
			(size 0.4572 0.4572)
			(layers "F.Cu" "F.Mask" "F.Paste")
			(net "GND")
		)
		(pad "N43" smd circle
			(at 17.100042 -11.400028)
			(size 0.4572 0.4572)
			(layers "F.Cu" "F.Mask" "F.Paste")
			(net "P5E_PEX2_STN4_TX_DP<67>")
		)
		(pad "N44" smd circle
			(at 18.050002 -11.400028)
			(size 0.4572 0.4572)
			(layers "F.Cu" "F.Mask" "F.Paste")
			(net "P5E_PEX2_STN4_TX_DN<67>")
		)
		(pad "N45" smd circle
			(at 18.999962 -11.400028)
			(size 0.4572 0.4572)
			(layers "F.Cu" "F.Mask" "F.Paste")
			(net "GND")
		)
		(pad "N46" smd circle
			(at 19.949922 -11.400028)
			(size 0.4572 0.4572)
			(layers "F.Cu" "F.Mask" "F.Paste")
			(net "P5E_PEX2_STN4_RX_DP<67>")
		)
		(pad "N47" smd circle
			(at 20.899882 -11.400028)
			(size 0.4572 0.4572)
			(layers "F.Cu" "F.Mask" "F.Paste")
			(net "P5E_PEX2_STN4_RX_DN<67>")
		)
		(pad "N48" smd circle
			(at 21.850096 -11.400028)
			(size 0.4572 0.4572)
			(layers "F.Cu" "F.Mask" "F.Paste")
			(net "GND")
		)
		(pad "N49" smd circle
			(at 22.800056 -11.400028)
			(size 0.4572 0.4572)
			(layers "F.Cu" "F.Mask" "F.Paste")
			(net "GND")
		)
		(pad "P1" smd circle
			(at -22.800056 -10.450068)
			(size 0.4572 0.4572)
			(layers "F.Cu" "F.Mask" "F.Paste")
			(net "P5E_PEX2_STN7_RX_DN<117>")
		)
		(pad "P2" smd circle
			(at -21.850096 -10.450068)
			(size 0.4572 0.4572)
			(layers "F.Cu" "F.Mask" "F.Paste")
			(net "P5E_PEX2_STN7_RX_DP<117>")
		)
		(pad "P3" smd circle
			(at -20.899882 -10.450068)
			(size 0.4572 0.4572)
			(layers "F.Cu" "F.Mask" "F.Paste")
			(net "GND")
		)
		(pad "P4" smd circle
			(at -19.949922 -10.450068)
			(size 0.4572 0.4572)
			(layers "F.Cu" "F.Mask" "F.Paste")
			(net "GND")
		)
		(pad "P5" smd circle
			(at -18.999962 -10.450068)
			(size 0.4572 0.4572)
			(layers "F.Cu" "F.Mask" "F.Paste")
			(net "GND")
		)
		(pad "P6" smd circle
			(at -18.050002 -10.450068)
			(size 0.4572 0.4572)
			(layers "F.Cu" "F.Mask" "F.Paste")
			(net "GND")
		)
		(pad "P7" smd circle
			(at -17.100042 -10.450068)
			(size 0.4572 0.4572)
			(layers "F.Cu" "F.Mask" "F.Paste")
			(net "GND")
		)
		(pad "P8" smd circle
			(at -16.150082 -10.450068)
			(size 0.4572 0.4572)
			(layers "F.Cu" "F.Mask" "F.Paste")
			(net "P5E_PEX2_STN7_TX_DN<117>")
		)
		(pad "P9" smd circle
			(at -15.200122 -10.450068)
			(size 0.4572 0.4572)
			(layers "F.Cu" "F.Mask" "F.Paste")
			(net "P5E_PEX2_STN7_TX_DP<117>")
		)
		(pad "P10" smd circle
			(at -14.249908 -10.450068)
			(size 0.4572 0.4572)
			(layers "F.Cu" "F.Mask" "F.Paste")
			(net "GND")
		)
		(pad "P11" smd circle
			(at -13.299948 -10.450068)
			(size 0.4572 0.4572)
			(layers "F.Cu" "F.Mask" "F.Paste")
			(net "GND")
		)
		(pad "P12" smd circle
			(at -12.349988 -10.450068)
			(size 0.4572 0.4572)
			(layers "F.Cu" "F.Mask" "F.Paste")
			(net "GND")
		)
		(pad "P13" smd circle
			(at -11.400028 -10.450068)
			(size 0.4572 0.4572)
			(layers "F.Cu" "F.Mask" "F.Paste")
			(net "GND")
		)
		(pad "P14" smd circle
			(at -10.450068 -10.450068)
			(size 0.4572 0.4572)
			(layers "F.Cu" "F.Mask" "F.Paste")
			(net "GND")
		)
		(pad "P15" smd circle
			(at -9.500108 -10.450068)
			(size 0.4572 0.4572)
			(layers "F.Cu" "F.Mask" "F.Paste")
			(net "GND")
		)
		(pad "P16" smd circle
			(at -8.549894 -10.450068)
			(size 0.4572 0.4572)
			(layers "F.Cu" "F.Mask" "F.Paste")
			(net "GND")
		)
		(pad "P17" smd circle
			(at -7.599934 -10.450068)
			(size 0.4572 0.4572)
			(layers "F.Cu" "F.Mask" "F.Paste")
			(net "GND")
		)
		(pad "P18" smd circle
			(at -6.649974 -10.450068)
			(size 0.4572 0.4572)
			(layers "F.Cu" "F.Mask" "F.Paste")
			(net "GND")
		)
		(pad "P19" smd circle
			(at -5.700014 -10.450068)
			(size 0.4572 0.4572)
			(layers "F.Cu" "F.Mask" "F.Paste")
			(net "GND")
		)
		(pad "P20" smd circle
			(at -4.750054 -10.450068)
			(size 0.4572 0.4572)
			(layers "F.Cu" "F.Mask" "F.Paste")
			(net "GND")
		)
		(pad "P21" smd circle
			(at -3.800094 -10.450068)
			(size 0.4572 0.4572)
			(layers "F.Cu" "F.Mask" "F.Paste")
			(net "GND")
		)
		(pad "P22" smd circle
			(at -2.84988 -10.450068)
			(size 0.4572 0.4572)
			(layers "F.Cu" "F.Mask" "F.Paste")
			(net "GND")
		)
		(pad "P23" smd circle
			(at -1.89992 -10.450068)
			(size 0.4572 0.4572)
			(layers "F.Cu" "F.Mask" "F.Paste")
			(net "GND")
		)
		(pad "P24" smd circle
			(at -0.94996 -10.450068)
			(size 0.4572 0.4572)
			(layers "F.Cu" "F.Mask" "F.Paste")
			(net "GND")
		)
		(pad "P25" smd circle
			(at 0 -10.450068)
			(size 0.4572 0.4572)
			(layers "F.Cu" "F.Mask" "F.Paste")
			(net "GND")
		)
		(pad "P26" smd circle
			(at 0.94996 -10.450068)
			(size 0.4572 0.4572)
			(layers "F.Cu" "F.Mask" "F.Paste")
			(net "GND")
		)
		(pad "P27" smd circle
			(at 1.89992 -10.450068)
			(size 0.4572 0.4572)
			(layers "F.Cu" "F.Mask" "F.Paste")
			(net "GND")
		)
		(pad "P28" smd circle
			(at 2.84988 -10.450068)
			(size 0.4572 0.4572)
			(layers "F.Cu" "F.Mask" "F.Paste")
			(net "GND")
		)
		(pad "P29" smd circle
			(at 3.800094 -10.450068)
			(size 0.4572 0.4572)
			(layers "F.Cu" "F.Mask" "F.Paste")
			(net "GND")
		)
		(pad "P30" smd circle
			(at 4.750054 -10.450068)
			(size 0.4572 0.4572)
			(layers "F.Cu" "F.Mask" "F.Paste")
			(net "GND")
		)
		(pad "P31" smd circle
			(at 5.700014 -10.450068)
			(size 0.4572 0.4572)
			(layers "F.Cu" "F.Mask" "F.Paste")
			(net "GND")
		)
		(pad "P32" smd circle
			(at 6.649974 -10.450068)
			(size 0.4572 0.4572)
			(layers "F.Cu" "F.Mask" "F.Paste")
			(net "GND")
		)
		(pad "P33" smd circle
			(at 7.599934 -10.450068)
			(size 0.4572 0.4572)
			(layers "F.Cu" "F.Mask" "F.Paste")
			(net "GND")
		)
		(pad "P34" smd circle
			(at 8.549894 -10.450068)
			(size 0.4572 0.4572)
			(layers "F.Cu" "F.Mask" "F.Paste")
			(net "GND")
		)
		(pad "P35" smd circle
			(at 9.500108 -10.450068)
			(size 0.4572 0.4572)
			(layers "F.Cu" "F.Mask" "F.Paste")
			(net "GND")
		)
		(pad "P36" smd circle
			(at 10.450068 -10.450068)
			(size 0.4572 0.4572)
			(layers "F.Cu" "F.Mask" "F.Paste")
			(net "Net_517")
		)
		(pad "P37" smd circle
			(at 11.400028 -10.450068)
			(size 0.4572 0.4572)
			(layers "F.Cu" "F.Mask" "F.Paste")
			(net "GND")
		)
		(pad "P38" smd circle
			(at 12.349988 -10.450068)
			(size 0.4572 0.4572)
			(layers "F.Cu" "F.Mask" "F.Paste")
			(net "RST_PEX2_S3_PERST_R_N")
		)
		(pad "P39" smd circle
			(at 13.299948 -10.450068)
			(size 0.4572 0.4572)
			(layers "F.Cu" "F.Mask" "F.Paste")
			(net "RST_PEX2_S1_PERST_R_N")
		)
		(pad "P40" smd circle
			(at 14.249908 -10.450068)
			(size 0.4572 0.4572)
			(layers "F.Cu" "F.Mask" "F.Paste")
			(net "GND")
		)
		(pad "P41" smd circle
			(at 15.200122 -10.450068)
			(size 0.4572 0.4572)
			(layers "F.Cu" "F.Mask" "F.Paste")
			(net "P5E_PEX2_STN4_TX_DP<66>")
		)
		(pad "P42" smd circle
			(at 16.150082 -10.450068)
			(size 0.4572 0.4572)
			(layers "F.Cu" "F.Mask" "F.Paste")
			(net "P5E_PEX2_STN4_TX_DN<66>")
		)
		(pad "P43" smd circle
			(at 17.100042 -10.450068)
			(size 0.4572 0.4572)
			(layers "F.Cu" "F.Mask" "F.Paste")
			(net "GND")
		)
		(pad "P44" smd circle
			(at 18.050002 -10.450068)
			(size 0.4572 0.4572)
			(layers "F.Cu" "F.Mask" "F.Paste")
			(net "GND")
		)
		(pad "P45" smd circle
			(at 18.999962 -10.450068)
			(size 0.4572 0.4572)
			(layers "F.Cu" "F.Mask" "F.Paste")
			(net "GND")
		)
		(pad "P46" smd circle
			(at 19.949922 -10.450068)
			(size 0.4572 0.4572)
			(layers "F.Cu" "F.Mask" "F.Paste")
			(net "GND")
		)
		(pad "P47" smd circle
			(at 20.899882 -10.450068)
			(size 0.4572 0.4572)
			(layers "F.Cu" "F.Mask" "F.Paste")
			(net "GND")
		)
		(pad "P48" smd circle
			(at 21.850096 -10.450068)
			(size 0.4572 0.4572)
			(layers "F.Cu" "F.Mask" "F.Paste")
			(net "P5E_PEX2_STN4_RX_DP<66>")
		)
		(pad "P49" smd circle
			(at 22.800056 -10.450068)
			(size 0.4572 0.4572)
			(layers "F.Cu" "F.Mask" "F.Paste")
			(net "P5E_PEX2_STN4_RX_DN<66>")
		)
		(pad "R1" smd circle
			(at -22.800056 -9.500108)
			(size 0.4572 0.4572)
			(layers "F.Cu" "F.Mask" "F.Paste")
			(net "GND")
		)
		(pad "R2" smd circle
			(at -21.850096 -9.500108)
			(size 0.4572 0.4572)
			(layers "F.Cu" "F.Mask" "F.Paste")
			(net "GND")
		)
		(pad "R3" smd circle
			(at -20.899882 -9.500108)
			(size 0.4572 0.4572)
			(layers "F.Cu" "F.Mask" "F.Paste")
			(net "P5E_PEX2_STN7_RX_DN<116>")
		)
		(pad "R4" smd circle
			(at -19.949922 -9.500108)
			(size 0.4572 0.4572)
			(layers "F.Cu" "F.Mask" "F.Paste")
			(net "P5E_PEX2_STN7_RX_DP<116>")
		)
		(pad "R5" smd circle
			(at -18.999962 -9.500108)
			(size 0.4572 0.4572)
			(layers "F.Cu" "F.Mask" "F.Paste")
			(net "GND")
		)
		(pad "R6" smd circle
			(at -18.050002 -9.500108)
			(size 0.4572 0.4572)
			(layers "F.Cu" "F.Mask" "F.Paste")
			(net "P5E_PEX2_STN7_TX_DN<116>")
		)
		(pad "R7" smd circle
			(at -17.100042 -9.500108)
			(size 0.4572 0.4572)
			(layers "F.Cu" "F.Mask" "F.Paste")
			(net "P5E_PEX2_STN7_TX_DP<116>")
		)
		(pad "R8" smd circle
			(at -16.150082 -9.500108)
			(size 0.4572 0.4572)
			(layers "F.Cu" "F.Mask" "F.Paste")
			(net "GND")
		)
		(pad "R9" smd circle
			(at -15.200122 -9.500108)
			(size 0.4572 0.4572)
			(layers "F.Cu" "F.Mask" "F.Paste")
			(net "GND")
		)
		(pad "R10" smd circle
			(at -14.249908 -9.500108)
			(size 0.4572 0.4572)
			(layers "F.Cu" "F.Mask" "F.Paste")
			(net "GND")
		)
		(pad "R11" smd circle
			(at -13.299948 -9.500108)
			(size 0.4572 0.4572)
			(layers "F.Cu" "F.Mask" "F.Paste")
			(net "GND")
		)
		(pad "R12" smd circle
			(at -12.349988 -9.500108)
			(size 0.4572 0.4572)
			(layers "F.Cu" "F.Mask" "F.Paste")
			(net "GND")
		)
		(pad "R13" smd circle
			(at -11.400028 -9.500108)
			(size 0.4572 0.4572)
			(layers "F.Cu" "F.Mask" "F.Paste")
			(net "GND")
		)
		(pad "R14" smd circle
			(at -10.450068 -9.500108)
			(size 0.4572 0.4572)
			(layers "F.Cu" "F.Mask" "F.Paste")
			(net "GND")
		)
		(pad "R15" smd circle
			(at -9.500108 -9.500108)
			(size 0.4572 0.4572)
			(layers "F.Cu" "F.Mask" "F.Paste")
			(net "GND")
		)
		(pad "R16" smd circle
			(at -8.549894 -9.500108)
			(size 0.4572 0.4572)
			(layers "F.Cu" "F.Mask" "F.Paste")
			(net "GND")
		)
	)
)
